FILE_TYPE = CONNECTIVITY;
{Allegro Design Entry HDL 17.2-2016 S081 (4005846) 1/11/2022}
"PAGE_NUMBER" = 31;
0"NC";
1"P3V3_AUX\g";
2"P3V3_AUX\g";
3"P3V3_AUX\g";
4"P3V3_AUX\g";
5"P3V3_AUX\g";
6"P3V3_AUX\g";
7"P3V3_AUX\g";
8"GND\g";
9"GND\g";
10"GND\g";
11"GND\g";
12"GND\g";
13"GND\g";
14"GND\g";
15"GND\g";
16"GND\g";
17"SPA_SIN_SW_DBG_R";
18"UART_SYS_DBG_RX_R";
19"UART_SYS_DBG_RX";
20"SPA_SIN_SW_DBG";
21"BMC_CPLD_GPIO_2";
22"FM_DBG_SW_N";
23"PU_J13_P1";
24"FM_BIC_DEBUG_SW_N";
25"UART_BIC_GF_RXD";
26"FM_BIC_DEBUG_SW_N";
27"UART_BIC_GF_TXD";
28"SPA_SOUT_SW_BUF_R";
29"FM_DBG_SW_N";
30"UART_6_BMC_TXD_R";
31"SPA_SOUT_SW_DBG_R";
32"UART_SYS_DBG_TX_R";
33"SPA_SOUT_SW_DBG";
34"UART_SYS_DBG_TX";
35"UART_BIC_DBG_RX";
36"UART_6_BMC_TXD";
37"UART_BIC_DBG_RX_R";
38"UART_BIC_DBG_TX";
39"UART_6_BMC_RXD_R";
40"UART_BIC_DBG_TX_R";
41"UART_6_BMC_RXD";
42"FM_DBG_SW_N";
43"SPA_SIN_SW_BUF_R";
%"UNIVERSAL_GND"
"1","(-4150,4625)","2","logical_power","I10";
;
CDS_LIB"logical_power"
HDL_POWER"GND";
"A"12;
%"Q_CAP"
"1","(-4150,4825)","2","pure_quanta","I11";
;
VOLTAGE"25V"
PACK_TYPE"0402"
MATERIAL"X7R"
TOLERANCE"10%"
PART_NUMBER"CH4104K1B00"
VALUE"0.1UF"
CDS_LIB"pure_quanta"
LOCATION"C501"
$SEC"1"
CDS_SEC"1";
"B"
$PN"2"12;
"A"
$PN"1"2;
%"UNIVERSAL_POWER"
"1","(-4150,5100)","0","logical_power","I12";
;
HDL_POWER"P3V3_AUX"
CDS_LIB"logical_power";
"A"2;
%"UNIVERSAL_GND"
"1","(-4125,5825)","2","logical_power","I16";
;
CDS_LIB"logical_power"
HDL_POWER"GND";
"A"11;
%"Q_CAP"
"1","(-4125,6025)","2","pure_quanta","I17";
;
TOLERANCE"10%"
VOLTAGE"25V"
MATERIAL"X7R"
VALUE"0.1UF"
PART_NUMBER"CH4104K1B00"
PACK_TYPE"0402"
CDS_LIB"pure_quanta"
LOCATION"C500"
$SEC"1"
CDS_SEC"1";
"B"
$PN"2"11;
"A"
$PN"1"3;
%"UNIVERSAL_POWER"
"1","(-4125,6300)","0","logical_power","I18";
;
HDL_POWER"P3V3_AUX"
CDS_LIB"logical_power";
"A"3;
%"NC7SB3157"
"1","(-4650,5550)","0","pure_quanta","I23";
;
PART_NUMBER"ALSB3157000"
VALUE"NC7SB3157P6X"
MANUF_PN"NC7SB3157P6X"
MATERIAL"IC"
PACK_TYPE"SMLF"
CDS_LMAN_SYM_OUTLINE"-150,50,150,-150"
CDS_LIB"pure_quanta"
LOCATION"U50"
$SEC"1"
CDS_SEC"1";
"S"
$PN"6"26;
"B0"
$PN"3"39;
"B1"
$PN"1"40;
"VCC"
$PN"5"3;
"GND"
$PN"2"8;
"A"
$PN"4"25;
%"NC7SB3157"
"1","(-4625,4400)","0","pure_quanta","I24";
;
MATERIAL"IC"
PART_NUMBER"ALSB3157000"
VALUE"NC7SB3157P6X"
MANUF_PN"NC7SB3157P6X"
PACK_TYPE"SMLF"
CDS_LMAN_SYM_OUTLINE"-150,50,150,-150"
CDS_LIB"pure_quanta"
LOCATION"U51"
$SEC"1"
CDS_SEC"1";
"S"
$PN"6"24;
"B0"
$PN"3"30;
"B1"
$PN"1"37;
"VCC"
$PN"5"2;
"GND"
$PN"2"13;
"A"
$PN"4"27;
%"Q_RES"
"2","(-5900,6050)","0","pure_quanta","I25";
;
VALUE"100K"
TOLERANCE"1%"
MATERIAL"CHIP"
WATTAGE"1/16W"
PART_NUMBER"CS41002FB09"
PACK_TYPE"0402LF"
CDS_LIB"pure_quanta"
$LOCATION"R538"
CDS_LOCATION"R538"
$SEC"1"
CDS_SEC"1";
"A"
$PN"1"4;
"B"
$PN"2"39;
%"UNIVERSAL_POWER"
"1","(-5900,6325)","0","logical_power","I26";
;
HDL_POWER"P3V3_AUX"
CDS_LIB"logical_power";
"A"4;
%"NC7SB3157"
"1","(-4600,2925)","0","pure_quanta","I27";
;
VALUE"NC7SB3157P6X"
MATERIAL"IC"
PART_NUMBER"ALSB3157000"
MANUF_PN"NC7SB3157P6X"
CDS_LIB"pure_quanta"
CDS_LMAN_SYM_OUTLINE"-150,50,150,-150"
PACK_TYPE"SMLF"
$LOCATION"U7"
CDS_LOCATION"U7"
$SEC"1"
CDS_SEC"1";
"S"
$PN"6"29;
"B0"
$PN"3"32;
"B1"
$PN"1"31;
"VCC"
$PN"5"5;
"GND"
$PN"2"14;
"A"
$PN"4"28;
%"UNIVERSAL_POWER"
"1","(-4125,3625)","0","logical_power","I30";
;
HDL_POWER"P3V3_AUX"
CDS_LIB"logical_power";
"A"5;
%"Q_CAP"
"1","(-4125,3350)","2","pure_quanta","I31";
;
VOLTAGE"25V"
PACK_TYPE"0402"
PART_NUMBER"CH4104K1B00"
MATERIAL"X7R"
TOLERANCE"10%"
VALUE"0.1UF"
CDS_LIB"pure_quanta"
$LOCATION"C11"
CDS_LOCATION"C11"
$SEC"1"
CDS_SEC"1";
"B"
$PN"2"15;
"A"
$PN"1"5;
%"UNIVERSAL_GND"
"1","(-4125,3150)","2","logical_power","I32";
;
HDL_POWER"GND"
CDS_LIB"logical_power";
"A"15;
%"UNIVERSAL_GND"
"1","(-5025,2650)","2","logical_power","I33";
;
CDS_LIB"logical_power"
HDL_POWER"GND";
"A"14;
%"NC7SB3157"
"1","(-4500,1325)","0","pure_quanta","I38";
;
MANUF_PN"NC7SB3157P6X"
VALUE"NC7SB3157P6X"
PART_NUMBER"ALSB3157000"
MATERIAL"IC"
PACK_TYPE"SMLF"
CDS_LMAN_SYM_OUTLINE"-150,50,150,-150"
CDS_LIB"pure_quanta"
$LOCATION"U20"
CDS_LOCATION"U20"
$SEC"1"
CDS_SEC"1";
"S"
$PN"6"42;
"B0"
$PN"3"18;
"B1"
$PN"1"17;
"VCC"
$PN"5"7;
"GND"
$PN"2"10;
"A"
$PN"4"43;
%"UNIVERSAL_GND"
"1","(-4925,1050)","2","logical_power","I43";
;
CDS_LIB"logical_power"
HDL_POWER"GND";
"A"10;
%"UNIVERSAL_GND"
"1","(-4025,1550)","2","logical_power","I44";
;
CDS_LIB"logical_power"
HDL_POWER"GND";
"A"16;
%"Q_CAP"
"1","(-4025,1750)","2","pure_quanta","I45";
;
PACK_TYPE"0402"
MATERIAL"X7R"
TOLERANCE"10%"
PART_NUMBER"CH4104K1B00"
VOLTAGE"25V"
VALUE"0.1UF"
CDS_LIB"pure_quanta"
$LOCATION"C231"
CDS_LOCATION"C231"
$SEC"1"
CDS_SEC"1";
"B"
$PN"2"16;
"A"
$PN"1"7;
%"UNIVERSAL_POWER"
"1","(-4025,2025)","0","logical_power","I46";
;
HDL_POWER"P3V3_AUX"
CDS_LIB"logical_power";
"A"7;
%"UNIVERSAL_GND"
"1","(-2100,1750)","2","logical_power","I52";
;
HDL_POWER"GND"
CDS_LIB"logical_power";
"A"9;
%"UNIVERSAL_POWER"
"1","(-2175,2550)","0","logical_power","I54";
;
HDL_POWER"P3V3_AUX"
CDS_LIB"logical_power";
"A"6;
%"SCONN3_212H9103GBR1"
"1","(-1450,2025)","0","pure_quanta","I61";
;
PART_TYPE"SMLF"
VALUE"SCONN3_212-H91-03GBR1"
PART_NUMBER"DFHD03MS161"
MATERIAL"EMPTY"
NEEDS_NO_SIZE"TRUE"
CDS_LMAN_SYM_OUTLINE"-50,100,50,-100"
CDS_LIB"pure_quanta"
LOCATION"J13"
$SEC"1"
CDS_SEC"1";
"1"
$PN"1"23;
"2"
$PN"2"22;
"3"
$PN"3"9;
%"UNIVERSAL_GND"
"1","(-5075,5300)","2","logical_power","I7";
;
CDS_LIB"logical_power"
HDL_POWER"GND";
"A"8;
%"Q_RES"
"1","(-6175,5550)","0","pure_quanta","I70";
;
MATERIAL"CHIP"
VALUE"0"
TOLERANCE"5%"
WATTAGE"1/16W"
PACK_TYPE"0402LF"
PART_NUMBER"CS00002JB13"
CDS_LIB"pure_quanta"
LOCATION"R900"
$SEC"1"
CDS_SEC"1";
"B"
$PN"2"40;
"A"
$PN"1"38;
%"Q_RES"
"1","(-6300,5450)","0","pure_quanta","I71";
;
MATERIAL"CHIP"
VALUE"0"
TOLERANCE"5%"
WATTAGE"1/16W"
PACK_TYPE"0402LF"
PART_NUMBER"CS00002JB13"
CDS_LIB"pure_quanta"
LOCATION"R901"
$SEC"1"
CDS_SEC"1";
"B"
$PN"2"39;
"A"
$PN"1"41;
%"Q_RES"
"1","(-6200,4400)","0","pure_quanta","I72";
;
MATERIAL"CHIP"
VALUE"0"
TOLERANCE"5%"
WATTAGE"1/16W"
PACK_TYPE"0402LF"
PART_NUMBER"CS00002JB13"
CDS_LIB"pure_quanta"
LOCATION"R902"
$SEC"1"
CDS_SEC"1";
"B"
$PN"2"37;
"A"
$PN"1"35;
%"Q_RES"
"1","(-6200,4300)","0","pure_quanta","I73";
;
MATERIAL"CHIP"
VALUE"0"
TOLERANCE"5%"
WATTAGE"1/16W"
PACK_TYPE"0402LF"
PART_NUMBER"CS00002JB13"
CDS_LIB"pure_quanta"
LOCATION"R903"
$SEC"1"
CDS_SEC"1";
"B"
$PN"2"30;
"A"
$PN"1"36;
%"Q_RES"
"1","(-6175,2825)","0","pure_quanta","I74";
;
PART_NUMBER"CS00002JB13"
TOLERANCE"5%"
VALUE"0"
MATERIAL"CHIP"
PACK_TYPE"0402LF"
CDS_LIB"pure_quanta"
WATTAGE"1/16W"
LOCATION"R544"
$SEC"1"
CDS_SEC"1";
"B"
$PN"2"32;
"A"
$PN"1"34;
%"Q_RES"
"1","(-6175,2925)","0","pure_quanta","I75";
;
MATERIAL"CHIP"
VALUE"0"
PART_NUMBER"CS00002JB13"
TOLERANCE"5%"
PACK_TYPE"0402LF"
WATTAGE"1/16W"
CDS_LIB"pure_quanta"
LOCATION"R546"
$SEC"1"
CDS_SEC"1";
"B"
$PN"2"31;
"A"
$PN"1"33;
%"Q_RES"
"1","(-6075,1225)","0","pure_quanta","I76";
;
MATERIAL"CHIP"
PACK_TYPE"0402LF"
VALUE"0"
TOLERANCE"5%"
PART_NUMBER"CS00002JB13"
WATTAGE"1/16W"
CDS_LIB"pure_quanta"
LOCATION"R618"
$SEC"1"
CDS_SEC"1";
"B"
$PN"2"18;
"A"
$PN"1"19;
%"Q_RES"
"1","(-6075,1325)","0","pure_quanta","I77";
;
MATERIAL"CHIP"
PACK_TYPE"0402LF"
VALUE"100"
TOLERANCE"1%"
PART_NUMBER"CS11002FB07"
CDS_LIB"pure_quanta"
WATTAGE"1/16W"
LOCATION"R628"
$SEC"1"
CDS_SEC"1";
"B"
$PN"2"17;
"A"
$PN"1"20;
%"Q_RES"
"1","(-2550,2225)","0","pure_quanta","I78";
;
VALUE"0"
MATERIAL"CHIP"
TOLERANCE"5%"
PART_NUMBER"CS00002JB13"
PACK_TYPE"0402LF"
WATTAGE"1/16W"
CDS_LIB"pure_quanta"
LOCATION"R629"
$SEC"1"
CDS_SEC"1";
"B"
$PN"2"22;
"A"
$PN"1"21;
%"Q_RES"
"2","(-2175,2325)","0","pure_quanta","I79";
;
PART_NUMBER"CS24702FB06"
WATTAGE"1/16W"
TOLERANCE"1%"
VALUE"4.7K"
PACK_TYPE"0402LF"
MATERIAL"CHIP"
CDS_LIB"pure_quanta"
LOCATION"R630"
$SEC"1"
CDS_SEC"1";
"A"
$PN"1"6;
"B"
$PN"2"23;
%"Q_RES"
"2","(-2000,5825)","0","pure_quanta","I80";
;
TOLERANCE"1%"
PACK_TYPE"0402LF"
MATERIAL"CHIP"
WATTAGE"1/16W"
VALUE"100K"
PART_NUMBER"CS41002FB09"
CDS_LIB"pure_quanta"
$LOCATION"R396"
CDS_LOCATION"R396"
$SEC"1"
CDS_SEC"1";
"A"
$PN"1"1;
"B"
$PN"2"25;
%"UNIVERSAL_POWER"
"1","(-2000,6125)","0","logical_power","I81";
;
HDL_POWER"P3V3_AUX"
CDS_LIB"logical_power";
"A"1;
%"UNIVERSAL_GND"
"1","(-5050,4125)","2","logical_power","I9";
;
HDL_POWER"GND"
CDS_LIB"logical_power";
"A"13;
END.
